(kicad_pcb
	(version 20260206)
	(generator "pcbnew")
	(generator_version "10.0")
	(general
		(thickness 1.6)
		(legacy_teardrops no)
	)
	(paper "A4")
	(title_block
		(title "Bryce Canyon_IOM_M2_16342-2_OCP.brd")
		(comment 1 "Bryce Canyon / footprints 872-879 of 1146")
	)
	(layers
		(0 "F.Cu" signal "TOP")
		(4 "In1.Cu" signal "L2GND")
		(6 "In2.Cu" signal "L3")
		(8 "In3.Cu" signal "L4VCC")
		(10 "In4.Cu" signal "L5VCC")
		(12 "In5.Cu" signal "L6")
		(14 "In6.Cu" signal "L7GND")
		(2 "B.Cu" signal "BOTTOM")
		(9 "F.Adhes" user "F.Adhesive")
		(11 "B.Adhes" user "B.Adhesive")
		(13 "F.Paste" user "Package Geometry/Pastemask Top")
		(15 "B.Paste" user "Package Geometry/Pastemask Bottom")
		(5 "F.SilkS" user "Ref Des/Silkscreen Top")
		(7 "B.SilkS" user "Ref Des/Silkscreen Bottom")
		(1 "F.Mask" user "Board Geometry/Soldermask Top")
		(3 "B.Mask" user "Board Geometry/Soldermask Bottom")
		(17 "Dwgs.User" user "User.Drawings")
		(19 "Cmts.User" user "User.Comments")
		(21 "Eco1.User" user "User.Eco1")
		(23 "Eco2.User" user "User.Eco2")
		(25 "Edge.Cuts" user "Board Geometry/Outline")
		(27 "Margin" user)
		(31 "F.CrtYd" user "Package Geometry/Place Bound Top")
		(29 "B.CrtYd" user "Package Geometry/Place Bound Bottom")
		(35 "F.Fab" user "Ref Des/Assembly Top")
		(33 "B.Fab" user "Ref Des/Assembly Bottom")
	)
	(footprint ""
		(layer "B.Cu")
		(at 194.425062 -133.83895 180)
		(property "Reference" "C605"
			(at 0 0 0)
			(layer "B.SilkS")
			(hide yes)
			(effects
				(font
					(size 1.27 1.27)
				)
				(justify mirror)
			)
		)
		(property "Value" "SCD1U16V2KX-3GP"
			(at -1.1811 -2.7051 180)
			(unlocked yes)
			(layer "B.Fab")
			(hide yes)
			(effects
				(font
					(size 1.016 1.016)
					(thickness 0.1524)
				)
				(justify mirror)
			)
		)
		(property "Device Type" "C402H22"
			(at -1.1811 -4.2291 180)
			(unlocked yes)
			(layer "B.Fab")
			(hide yes)
			(effects
				(font
					(size 1.016 1.016)
					(thickness 0.1524)
				)
				(justify mirror)
			)
		)
		(duplicate_pad_numbers_are_jumpers no)
		(fp_rect
			(start 0.4318 0.9525)
			(end -0.4318 -0.9525)
			(stroke
				(width 0)
				(type default)
			)
			(fill no)
			(layer "B.CrtYd")
		)
		(fp_rect
			(start 0.4318 0.9525)
			(end -0.4318 -0.9525)
			(stroke
				(width 0)
				(type default)
			)
			(fill no)
			(layer "B.Fab")
		)
		(pad "1" smd custom
			(at 0 -0.4445)
			(size 0.1524 0.1524)
			(layers "B.Cu" "B.Mask" "B.Paste")
			(net "P3V3_M2")
			(options
				(clearance outline)
				(anchor circle)
			)
			(primitives
				(gr_poly
					(pts
						(arc
							(start 0.3048 0.2032)
							(mid 0.275042 0.275042)
							(end 0.2032 0.3048)
						)
						(arc
							(start -0.2032 0.3048)
							(mid -0.275042 0.275042)
							(end -0.3048 0.2032)
						)
						(arc
							(start -0.3048 -0.2032)
							(mid -0.275042 -0.275042)
							(end -0.2032 -0.3048)
						)
						(arc
							(start 0.2032 -0.3048)
							(mid 0.275042 -0.275042)
							(end 0.3048 -0.2032)
						)
					)
					(width 0)
					(fill yes)
				)
			)
		)
		(pad "2" smd custom
			(at 0 0.4445)
			(size 0.1524 0.1524)
			(layers "B.Cu" "B.Mask" "B.Paste")
			(net "GND")
			(options
				(clearance outline)
				(anchor circle)
			)
			(primitives
				(gr_poly
					(pts
						(arc
							(start 0.3048 0.2032)
							(mid 0.275042 0.275042)
							(end 0.2032 0.3048)
						)
						(arc
							(start -0.2032 0.3048)
							(mid -0.275042 0.275042)
							(end -0.3048 0.2032)
						)
						(arc
							(start -0.3048 -0.2032)
							(mid -0.275042 -0.275042)
							(end -0.2032 -0.3048)
						)
						(arc
							(start 0.2032 -0.3048)
							(mid 0.275042 -0.275042)
							(end 0.3048 -0.2032)
						)
					)
					(width 0)
					(fill yes)
				)
			)
		)
	)
	(footprint ""
		(layer "B.Cu")
		(at 170.035728 -122.580908 -90)
		(property "Reference" "C641"
			(at 0 0 90)
			(layer "B.SilkS")
			(hide yes)
			(effects
				(font
					(size 1.27 1.27)
				)
				(justify mirror)
			)
		)
		(property "Value" "SCD1U16V2KX-3GP"
			(at -1.1811 -2.7051 270)
			(unlocked yes)
			(layer "B.Fab")
			(hide yes)
			(effects
				(font
					(size 1.016 1.016)
					(thickness 0.1524)
				)
				(justify mirror)
			)
		)
		(property "Device Type" "C402H22"
			(at -1.1811 -4.2291 270)
			(unlocked yes)
			(layer "B.Fab")
			(hide yes)
			(effects
				(font
					(size 1.016 1.016)
					(thickness 0.1524)
				)
				(justify mirror)
			)
		)
		(duplicate_pad_numbers_are_jumpers no)
		(fp_rect
			(start 0.4318 0.9525)
			(end -0.4318 -0.9525)
			(stroke
				(width 0)
				(type default)
			)
			(fill no)
			(layer "B.CrtYd")
		)
		(fp_rect
			(start 0.4318 0.9525)
			(end -0.4318 -0.9525)
			(stroke
				(width 0)
				(type default)
			)
			(fill no)
			(layer "B.Fab")
		)
		(pad "1" smd custom
			(at 0 -0.4445 90)
			(size 0.1524 0.1524)
			(layers "B.Cu" "B.Mask" "B.Paste")
			(net "P3V3_M2")
			(options
				(clearance outline)
				(anchor circle)
			)
			(primitives
				(gr_poly
					(pts
						(arc
							(start 0.3048 0.2032)
							(mid 0.275042 0.275042)
							(end 0.2032 0.3048)
						)
						(arc
							(start -0.2032 0.3048)
							(mid -0.275042 0.275042)
							(end -0.3048 0.2032)
						)
						(arc
							(start -0.3048 -0.2032)
							(mid -0.275042 -0.275042)
							(end -0.2032 -0.3048)
						)
						(arc
							(start 0.2032 -0.3048)
							(mid 0.275042 -0.275042)
							(end 0.3048 -0.2032)
						)
					)
					(width 0)
					(fill yes)
				)
			)
		)
		(pad "2" smd custom
			(at 0 0.4445 90)
			(size 0.1524 0.1524)
			(layers "B.Cu" "B.Mask" "B.Paste")
			(net "GND")
			(options
				(clearance outline)
				(anchor circle)
			)
			(primitives
				(gr_poly
					(pts
						(arc
							(start 0.3048 0.2032)
							(mid 0.275042 0.275042)
							(end 0.2032 0.3048)
						)
						(arc
							(start -0.2032 0.3048)
							(mid -0.275042 0.275042)
							(end -0.3048 0.2032)
						)
						(arc
							(start -0.3048 -0.2032)
							(mid -0.275042 -0.275042)
							(end -0.2032 -0.3048)
						)
						(arc
							(start 0.2032 -0.3048)
							(mid 0.275042 -0.275042)
							(end 0.3048 -0.2032)
						)
					)
					(width 0)
					(fill yes)
				)
			)
		)
	)
	(footprint ""
		(layer "B.Cu")
		(at 51.0794 -122.682 -90)
		(property "Reference" "R341"
			(at 0 0 90)
			(layer "B.SilkS")
			(hide yes)
			(effects
				(font
					(size 1.27 1.27)
				)
				(justify mirror)
			)
		)
		(property "Value" "4K7R2F-GP"
			(at -0.064008 -3.993896 270)
			(unlocked yes)
			(layer "B.Fab")
			(hide yes)
			(effects
				(font
					(size 1.016 1.016)
					(thickness 0.1524)
				)
				(justify mirror)
			)
		)
		(property "Device Type" "R402H16"
			(at -0.064008 -5.517896 270)
			(unlocked yes)
			(layer "B.Fab")
			(hide yes)
			(effects
				(font
					(size 1.016 1.016)
					(thickness 0.1524)
				)
				(justify mirror)
			)
		)
		(duplicate_pad_numbers_are_jumpers no)
		(fp_line
			(start -0.508 -0.9398)
			(end 0.508 -0.9398)
			(stroke
				(width 0.1524)
				(type default)
			)
			(layer "B.SilkS")
		)
		(fp_line
			(start 0.508 -0.9398)
			(end 0.508 0.9398)
			(stroke
				(width 0.1524)
				(type default)
			)
			(layer "B.SilkS")
		)
		(fp_rect
			(start 0.508 0.9398)
			(end -0.508 -0.9398)
			(stroke
				(width 0)
				(type default)
			)
			(fill no)
			(layer "B.CrtYd")
		)
		(fp_rect
			(start 0.508 0.9398)
			(end -0.508 -0.9398)
			(stroke
				(width 0)
				(type default)
			)
			(fill no)
			(layer "B.Fab")
		)
		(pad "1" smd custom
			(at 0 -0.4445 90)
			(size 0.1397 0.1397)
			(layers "B.Cu" "B.Mask" "B.Paste")
			(net "TEMP_3_A2")
			(options
				(clearance outline)
				(anchor circle)
			)
			(primitives
				(gr_poly
					(pts
						(arc
							(start -0.1778 0.2794)
							(mid -0.249642 0.249642)
							(end -0.2794 0.1778)
						)
						(arc
							(start -0.2794 -0.1778)
							(mid -0.249642 -0.249642)
							(end -0.1778 -0.2794)
						)
						(arc
							(start 0.1778 -0.2794)
							(mid 0.249642 -0.249642)
							(end 0.2794 -0.1778)
						)
						(arc
							(start 0.2794 0.1778)
							(mid 0.249642 0.249642)
							(end 0.1778 0.2794)
						)
					)
					(width 0)
					(fill yes)
				)
			)
		)
		(pad "2" smd custom
			(at 0 0.4445 90)
			(size 0.1397 0.1397)
			(layers "B.Cu" "B.Mask" "B.Paste")
			(net "GND")
			(options
				(clearance outline)
				(anchor circle)
			)
			(primitives
				(gr_poly
					(pts
						(arc
							(start -0.1778 0.2794)
							(mid -0.249642 0.249642)
							(end -0.2794 0.1778)
						)
						(arc
							(start -0.2794 -0.1778)
							(mid -0.249642 -0.249642)
							(end -0.1778 -0.2794)
						)
						(arc
							(start 0.1778 -0.2794)
							(mid 0.249642 -0.249642)
							(end 0.2794 -0.1778)
						)
						(arc
							(start 0.2794 0.1778)
							(mid 0.249642 0.249642)
							(end 0.1778 0.2794)
						)
					)
					(width 0)
					(fill yes)
				)
			)
		)
	)
	(footprint ""
		(layer "B.Cu")
		(at 128.651 -14.351)
		(property "Reference" "C145"
			(at 0 0 0)
			(layer "B.SilkS")
			(hide yes)
			(effects
				(font
					(size 1.27 1.27)
				)
				(justify mirror)
			)
		)
		(property "Value" "SC1U16V3KX-5GP"
			(at 0 -2.8194 0)
			(unlocked yes)
			(layer "B.Fab")
			(hide yes)
			(effects
				(font
					(size 1.016 1.016)
					(thickness 0.1524)
				)
				(justify mirror)
			)
		)
		(property "Device Type" "C603H36"
			(at 0 -4.3434 0)
			(unlocked yes)
			(layer "B.Fab")
			(hide yes)
			(effects
				(font
					(size 1.016 1.016)
					(thickness 0.1524)
				)
				(justify mirror)
			)
		)
		(duplicate_pad_numbers_are_jumpers no)
		(fp_line
			(start -0.508 0)
			(end 0.508 0)
			(stroke
				(width 0.2032)
				(type default)
			)
			(layer "B.SilkS")
		)
		(fp_rect
			(start 0.5842 1.3335)
			(end -0.5842 -1.3335)
			(stroke
				(width 0)
				(type default)
			)
			(fill no)
			(layer "B.CrtYd")
		)
		(fp_rect
			(start 0.5842 1.3335)
			(end -0.5842 -1.3335)
			(stroke
				(width 0)
				(type default)
			)
			(fill no)
			(layer "B.Fab")
		)
		(pad "1" smd custom
			(at 0 -0.762 180)
			(size 0.2159 0.2159)
			(layers "B.Cu" "B.Mask" "B.Paste")
			(net "MB0_CM_UV_R")
			(options
				(clearance outline)
				(anchor circle)
			)
			(primitives
				(gr_poly
					(pts
						(arc
							(start -0.3302 0.4318)
							(mid -0.402042 0.402042)
							(end -0.4318 0.3302)
						)
						(arc
							(start -0.4318 -0.3302)
							(mid -0.402042 -0.402042)
							(end -0.3302 -0.4318)
						)
						(arc
							(start 0.3302 -0.4318)
							(mid 0.402042 -0.402042)
							(end 0.4318 -0.3302)
						)
						(arc
							(start 0.4318 0.3302)
							(mid 0.402042 0.402042)
							(end 0.3302 0.4318)
						)
					)
					(width 0)
					(fill yes)
				)
			)
		)
		(pad "2" smd custom
			(at 0 0.762 180)
			(size 0.2159 0.2159)
			(layers "B.Cu" "B.Mask" "B.Paste")
			(net "AGND_CURRENT_MON")
			(options
				(clearance outline)
				(anchor circle)
			)
			(primitives
				(gr_poly
					(pts
						(arc
							(start -0.3302 0.4318)
							(mid -0.402042 0.402042)
							(end -0.4318 0.3302)
						)
						(arc
							(start -0.4318 -0.3302)
							(mid -0.402042 -0.402042)
							(end -0.3302 -0.4318)
						)
						(arc
							(start 0.3302 -0.4318)
							(mid 0.402042 -0.402042)
							(end 0.4318 -0.3302)
						)
						(arc
							(start 0.4318 0.3302)
							(mid 0.402042 0.402042)
							(end 0.3302 0.4318)
						)
					)
					(width 0)
					(fill yes)
				)
			)
		)
	)
	(footprint ""
		(layer "B.Cu")
		(at 12.7762 -148.9329 -90)
		(property "Reference" "C63"
			(at 0 0 90)
			(layer "B.SilkS")
			(hide yes)
			(effects
				(font
					(size 1.27 1.27)
				)
				(justify mirror)
			)
		)
		(property "Value" "SC4D7U25V5KX-1-GP"
			(at 0.0762 -6.1214 270)
			(unlocked yes)
			(layer "B.Fab")
			(hide yes)
			(effects
				(font
					(size 1.016 1.016)
					(thickness 0.1524)
				)
				(justify mirror)
			)
		)
		(property "Device Type" "C805H58"
			(at 0.0762 -8.1534 270)
			(unlocked yes)
			(layer "B.Fab")
			(hide yes)
			(effects
				(font
					(size 1.016 1.016)
					(thickness 0.1524)
				)
				(justify mirror)
			)
		)
		(duplicate_pad_numbers_are_jumpers no)
		(fp_line
			(start -0.635 0)
			(end 0.635 0)
			(stroke
				(width 0.508)
				(type default)
			)
			(layer "B.SilkS")
		)
		(fp_rect
			(start 0.9652 1.778)
			(end -0.9652 -1.778)
			(stroke
				(width 0)
				(type default)
			)
			(fill no)
			(layer "B.CrtYd")
		)
		(fp_poly
			(pts
				(xy 0.9652 -1.778) (xy -0.9652 -1.778) (xy -0.9652 1.778) (xy 0.9652 1.778)
			)
			(stroke
				(width 0)
				(type default)
			)
			(fill no)
			(layer "B.Fab")
		)
		(pad "1" smd rect
			(at 0 -0.9652 90)
			(size 1.397 1.143)
			(layers "B.Cu" "B.Mask" "B.Paste")
			(net "P1V2_STBY")
		)
		(pad "2" smd rect
			(at 0 0.9652 90)
			(size 1.397 1.143)
			(layers "B.Cu" "B.Mask" "B.Paste")
			(net "GND")
		)
	)
	(footprint ""
		(layer "B.Cu")
		(at 48.887634 -155.610052)
		(property "Reference" "R323"
			(at 0 0 0)
			(layer "B.SilkS")
			(hide yes)
			(effects
				(font
					(size 1.27 1.27)
				)
				(justify mirror)
			)
		)
		(property "Value" "4K7R2F-GP"
			(at -0.064008 -3.993896 0)
			(unlocked yes)
			(layer "B.Fab")
			(hide yes)
			(effects
				(font
					(size 1.016 1.016)
					(thickness 0.1524)
				)
				(justify mirror)
			)
		)
		(property "Device Type" "R402H16"
			(at -0.064008 -5.517896 0)
			(unlocked yes)
			(layer "B.Fab")
			(hide yes)
			(effects
				(font
					(size 1.016 1.016)
					(thickness 0.1524)
				)
				(justify mirror)
			)
		)
		(duplicate_pad_numbers_are_jumpers no)
		(fp_line
			(start -0.508 -0.9398)
			(end 0.508 -0.9398)
			(stroke
				(width 0.1524)
				(type default)
			)
			(layer "B.SilkS")
		)
		(fp_line
			(start 0.508 -0.9398)
			(end 0.508 0.9398)
			(stroke
				(width 0.1524)
				(type default)
			)
			(layer "B.SilkS")
		)
		(fp_rect
			(start 0.508 0.9398)
			(end -0.508 -0.9398)
			(stroke
				(width 0)
				(type default)
			)
			(fill no)
			(layer "B.CrtYd")
		)
		(fp_rect
			(start 0.508 0.9398)
			(end -0.508 -0.9398)
			(stroke
				(width 0)
				(type default)
			)
			(fill no)
			(layer "B.Fab")
		)
		(pad "1" smd custom
			(at 0 -0.4445 180)
			(size 0.1397 0.1397)
			(layers "B.Cu" "B.Mask" "B.Paste")
			(net "GND")
			(options
				(clearance outline)
				(anchor circle)
			)
			(primitives
				(gr_poly
					(pts
						(arc
							(start -0.1778 0.2794)
							(mid -0.249642 0.249642)
							(end -0.2794 0.1778)
						)
						(arc
							(start -0.2794 -0.1778)
							(mid -0.249642 -0.249642)
							(end -0.1778 -0.2794)
						)
						(arc
							(start 0.1778 -0.2794)
							(mid 0.249642 -0.249642)
							(end 0.2794 -0.1778)
						)
						(arc
							(start 0.2794 0.1778)
							(mid 0.249642 0.249642)
							(end 0.1778 0.2794)
						)
					)
					(width 0)
					(fill yes)
				)
			)
		)
		(pad "2" smd custom
			(at 0 0.4445 180)
			(size 0.1397 0.1397)
			(layers "B.Cu" "B.Mask" "B.Paste")
			(net "BOARD_REV_1")
			(options
				(clearance outline)
				(anchor circle)
			)
			(primitives
				(gr_poly
					(pts
						(arc
							(start -0.1778 0.2794)
							(mid -0.249642 0.249642)
							(end -0.2794 0.1778)
						)
						(arc
							(start -0.2794 -0.1778)
							(mid -0.249642 -0.249642)
							(end -0.1778 -0.2794)
						)
						(arc
							(start 0.1778 -0.2794)
							(mid 0.249642 -0.249642)
							(end 0.2794 -0.1778)
						)
						(arc
							(start 0.2794 0.1778)
							(mid 0.249642 0.249642)
							(end 0.1778 0.2794)
						)
					)
					(width 0)
					(fill yes)
				)
			)
		)
	)
	(footprint ""
		(layer "B.Cu")
		(at 129.921 -14.351)
		(property "Reference" "R448"
			(at 0 0 0)
			(layer "B.SilkS")
			(hide yes)
			(effects
				(font
					(size 1.27 1.27)
				)
				(justify mirror)
			)
		)
		(property "Value" "5K1R2F-3-GP"
			(at -0.064008 -3.993896 0)
			(unlocked yes)
			(layer "B.Fab")
			(hide yes)
			(effects
				(font
					(size 1.016 1.016)
					(thickness 0.1524)
				)
				(justify mirror)
			)
		)
		(property "Device Type" "R402H16"
			(at -0.064008 -5.517896 0)
			(unlocked yes)
			(layer "B.Fab")
			(hide yes)
			(effects
				(font
					(size 1.016 1.016)
					(thickness 0.1524)
				)
				(justify mirror)
			)
		)
		(duplicate_pad_numbers_are_jumpers no)
		(fp_line
			(start -0.508 -0.9398)
			(end 0.508 -0.9398)
			(stroke
				(width 0.1524)
				(type default)
			)
			(layer "B.SilkS")
		)
		(fp_line
			(start 0.508 -0.9398)
			(end 0.508 0.9398)
			(stroke
				(width 0.1524)
				(type default)
			)
			(layer "B.SilkS")
		)
		(fp_rect
			(start 0.508 0.9398)
			(end -0.508 -0.9398)
			(stroke
				(width 0)
				(type default)
			)
			(fill no)
			(layer "B.CrtYd")
		)
		(fp_rect
			(start 0.508 0.9398)
			(end -0.508 -0.9398)
			(stroke
				(width 0)
				(type default)
			)
			(fill no)
			(layer "B.Fab")
		)
		(pad "1" smd custom
			(at 0 -0.4445 180)
			(size 0.1397 0.1397)
			(layers "B.Cu" "B.Mask" "B.Paste")
			(net "MB0_CM_UV_R")
			(options
				(clearance outline)
				(anchor circle)
			)
			(primitives
				(gr_poly
					(pts
						(arc
							(start -0.1778 0.2794)
							(mid -0.249642 0.249642)
							(end -0.2794 0.1778)
						)
						(arc
							(start -0.2794 -0.1778)
							(mid -0.249642 -0.249642)
							(end -0.1778 -0.2794)
						)
						(arc
							(start 0.1778 -0.2794)
							(mid 0.249642 -0.249642)
							(end 0.2794 -0.1778)
						)
						(arc
							(start 0.2794 0.1778)
							(mid 0.249642 0.249642)
							(end 0.1778 0.2794)
						)
					)
					(width 0)
					(fill yes)
				)
			)
		)
		(pad "2" smd custom
			(at 0 0.4445 180)
			(size 0.1397 0.1397)
			(layers "B.Cu" "B.Mask" "B.Paste")
			(net "AGND_CURRENT_MON")
			(options
				(clearance outline)
				(anchor circle)
			)
			(primitives
				(gr_poly
					(pts
						(arc
							(start -0.1778 0.2794)
							(mid -0.249642 0.249642)
							(end -0.2794 0.1778)
						)
						(arc
							(start -0.2794 -0.1778)
							(mid -0.249642 -0.249642)
							(end -0.1778 -0.2794)
						)
						(arc
							(start 0.1778 -0.2794)
							(mid 0.249642 -0.249642)
							(end 0.2794 -0.1778)
						)
						(arc
							(start 0.2794 0.1778)
							(mid 0.249642 0.249642)
							(end 0.1778 0.2794)
						)
					)
					(width 0)
					(fill yes)
				)
			)
		)
	)
	(footprint ""
		(layer "B.Cu")
		(at 126.5301 -14.48562)
		(property "Reference" "R447"
			(at 0 0 0)
			(layer "B.SilkS")
			(hide yes)
			(effects
				(font
					(size 1.27 1.27)
				)
				(justify mirror)
			)
		)
		(property "Value" "4K12R2F-3-GP"
			(at -0.064008 -3.993896 0)
			(unlocked yes)
			(layer "B.Fab")
			(hide yes)
			(effects
				(font
					(size 1.016 1.016)
					(thickness 0.1524)
				)
				(justify mirror)
			)
		)
		(property "Device Type" "R402H16"
			(at -0.064008 -5.517896 0)
			(unlocked yes)
			(layer "B.Fab")
			(hide yes)
			(effects
				(font
					(size 1.016 1.016)
					(thickness 0.1524)
				)
				(justify mirror)
			)
		)
		(duplicate_pad_numbers_are_jumpers no)
		(fp_line
			(start -0.508 -0.9398)
			(end 0.508 -0.9398)
			(stroke
				(width 0.1524)
				(type default)
			)
			(layer "B.SilkS")
		)
		(fp_line
			(start 0.508 -0.9398)
			(end 0.508 0.9398)
			(stroke
				(width 0.1524)
				(type default)
			)
			(layer "B.SilkS")
		)
		(fp_rect
			(start 0.508 0.9398)
			(end -0.508 -0.9398)
			(stroke
				(width 0)
				(type default)
			)
			(fill no)
			(layer "B.CrtYd")
		)
		(fp_rect
			(start 0.508 0.9398)
			(end -0.508 -0.9398)
			(stroke
				(width 0)
				(type default)
			)
			(fill no)
			(layer "B.Fab")
		)
		(pad "1" smd custom
			(at 0 -0.4445 180)
			(size 0.1397 0.1397)
			(layers "B.Cu" "B.Mask" "B.Paste")
			(net "MB0_CM_OV_R")
			(options
				(clearance outline)
				(anchor circle)
			)
			(primitives
				(gr_poly
					(pts
						(arc
							(start -0.1778 0.2794)
							(mid -0.249642 0.249642)
							(end -0.2794 0.1778)
						)
						(arc
							(start -0.2794 -0.1778)
							(mid -0.249642 -0.249642)
							(end -0.1778 -0.2794)
						)
						(arc
							(start 0.1778 -0.2794)
							(mid 0.249642 -0.249642)
							(end 0.2794 -0.1778)
						)
						(arc
							(start 0.2794 0.1778)
							(mid 0.249642 0.249642)
							(end 0.1778 0.2794)
						)
					)
					(width 0)
					(fill yes)
				)
			)
		)
		(pad "2" smd custom
			(at 0 0.4445 180)
			(size 0.1397 0.1397)
			(layers "B.Cu" "B.Mask" "B.Paste")
			(net "AGND_CURRENT_MON")
			(options
				(clearance outline)
				(anchor circle)
			)
			(primitives
				(gr_poly
					(pts
						(arc
							(start -0.1778 0.2794)
							(mid -0.249642 0.249642)
							(end -0.2794 0.1778)
						)
						(arc
							(start -0.2794 -0.1778)
							(mid -0.249642 -0.249642)
							(end -0.1778 -0.2794)
						)
						(arc
							(start 0.1778 -0.2794)
							(mid 0.249642 -0.249642)
							(end 0.2794 -0.1778)
						)
						(arc
							(start 0.2794 0.1778)
							(mid 0.249642 0.249642)
							(end 0.1778 0.2794)
						)
					)
					(width 0)
					(fill yes)
				)
			)
		)
	)
)
